(kicad_pcb
	(version 20260206)
	(generator "pcbnew")
	(generator_version "10.0")
	(general
		(thickness 1.6)
		(legacy_teardrops no)
	)
	(paper "A4")
	(title_block
		(title "baseboard — 13948-1b.1110WZS1818.brd")
		(comment 1 "Honey Badger (Wiwynn) / footprints 986-992 of 2523")
	)
	(layers
		(0 "F.Cu" signal "TOP")
		(4 "In1.Cu" signal "L2GND")
		(6 "In2.Cu" signal "L3")
		(8 "In3.Cu" signal "L4VCC")
		(10 "In4.Cu" signal "L5VCC")
		(12 "In5.Cu" signal "L6")
		(14 "In6.Cu" signal "L7GND")
		(2 "B.Cu" signal "BOTTOM")
		(9 "F.Adhes" user "F.Adhesive")
		(11 "B.Adhes" user "B.Adhesive")
		(13 "F.Paste" user "Package Geometry/Pastemask Top")
		(15 "B.Paste" user "Package Geometry/Pastemask Bottom")
		(5 "F.SilkS" user "Ref Des/Silkscreen Top")
		(7 "B.SilkS" user "Ref Des/Silkscreen Bottom")
		(1 "F.Mask" user "Board Geometry/Soldermask Top")
		(3 "B.Mask" user "Board Geometry/Soldermask Bottom")
		(17 "Dwgs.User" user "User.Drawings")
		(19 "Cmts.User" user "User.Comments")
		(21 "Eco1.User" user "User.Eco1")
		(23 "Eco2.User" user "User.Eco2")
		(25 "Edge.Cuts" user "Board Geometry/Outline")
		(27 "Margin" user)
		(31 "F.CrtYd" user "Package Geometry/Place Bound Top")
		(29 "B.CrtYd" user "Package Geometry/Place Bound Bottom")
		(35 "F.Fab" user "Ref Des/Assembly Top")
		(33 "B.Fab" user "Ref Des/Assembly Bottom")
	)
	(footprint ""
		(layer "F.Cu")
		(at 195.834 -116.205)
		(property "Reference" "PC240"
			(at 0 0 0)
			(layer "F.SilkS")
			(hide yes)
			(effects
				(font
					(size 1.27 1.27)
				)
			)
		)
		(property "Value" "SC1U10V2KX-1GP"
			(at 1.1811 -2.7051 0)
			(unlocked yes)
			(layer "F.Fab")
			(hide yes)
			(effects
				(font
					(size 1.016 1.016)
					(thickness 0.1524)
				)
			)
		)
		(property "Device Type" "C402H22"
			(at 1.1811 -4.2291 0)
			(unlocked yes)
			(layer "F.Fab")
			(hide yes)
			(effects
				(font
					(size 1.016 1.016)
					(thickness 0.1524)
				)
			)
		)
		(duplicate_pad_numbers_are_jumpers no)
		(fp_rect
			(start -0.4318 0.9525)
			(end 0.4318 -0.9525)
			(stroke
				(width 0)
				(type default)
			)
			(fill no)
			(layer "F.CrtYd")
		)
		(fp_rect
			(start -0.4318 0.9525)
			(end 0.4318 -0.9525)
			(stroke
				(width 0)
				(type default)
			)
			(fill no)
			(layer "F.Fab")
		)
		(pad "1" smd custom
			(at 0 -0.4445)
			(size 0.1524 0.1524)
			(layers "F.Cu" "F.Mask" "F.Paste")
			(net "GND")
			(options
				(clearance outline)
				(anchor circle)
			)
			(primitives
				(gr_poly
					(pts
						(arc
							(start 0.3048 -0.2032)
							(mid 0.275042 -0.275042)
							(end 0.2032 -0.3048)
						)
						(arc
							(start -0.2032 -0.3048)
							(mid -0.275042 -0.275042)
							(end -0.3048 -0.2032)
						)
						(arc
							(start -0.3048 0.2032)
							(mid -0.275042 0.275042)
							(end -0.2032 0.3048)
						)
						(arc
							(start 0.2032 0.3048)
							(mid 0.275042 0.275042)
							(end 0.3048 0.2032)
						)
					)
					(width 0)
					(fill yes)
				)
			)
		)
		(pad "2" smd custom
			(at 0 0.4445)
			(size 0.1524 0.1524)
			(layers "F.Cu" "F.Mask" "F.Paste")
			(net "P1V5_E_EN_R")
			(options
				(clearance outline)
				(anchor circle)
			)
			(primitives
				(gr_poly
					(pts
						(arc
							(start 0.3048 -0.2032)
							(mid 0.275042 -0.275042)
							(end 0.2032 -0.3048)
						)
						(arc
							(start -0.2032 -0.3048)
							(mid -0.275042 -0.275042)
							(end -0.3048 -0.2032)
						)
						(arc
							(start -0.3048 0.2032)
							(mid -0.275042 0.275042)
							(end -0.2032 0.3048)
						)
						(arc
							(start 0.2032 0.3048)
							(mid 0.275042 0.275042)
							(end 0.3048 0.2032)
						)
					)
					(width 0)
					(fill yes)
				)
			)
		)
	)
	(footprint ""
		(layer "F.Cu")
		(at 25.985216 -225.73488)
		(property "Reference" "R635"
			(at 0 0 0)
			(layer "F.SilkS")
			(hide yes)
			(effects
				(font
					(size 1.27 1.27)
				)
			)
		)
		(property "Value" "4K7R2F-GP"
			(at 0.064008 -3.993896 0)
			(unlocked yes)
			(layer "F.Fab")
			(hide yes)
			(effects
				(font
					(size 1.016 1.016)
					(thickness 0.1524)
				)
			)
		)
		(property "Device Type" "R402H16"
			(at 0.064008 -5.517896 0)
			(unlocked yes)
			(layer "F.Fab")
			(hide yes)
			(effects
				(font
					(size 1.016 1.016)
					(thickness 0.1524)
				)
			)
		)
		(duplicate_pad_numbers_are_jumpers no)
		(fp_line
			(start -0.508 -0.9398)
			(end -0.508 0.9398)
			(stroke
				(width 0.1524)
				(type default)
			)
			(layer "F.SilkS")
		)
		(fp_line
			(start 0.508 -0.9398)
			(end -0.508 -0.9398)
			(stroke
				(width 0.1524)
				(type default)
			)
			(layer "F.SilkS")
		)
		(fp_rect
			(start -0.508 0.9398)
			(end 0.508 -0.9398)
			(stroke
				(width 0)
				(type default)
			)
			(fill no)
			(layer "F.CrtYd")
		)
		(fp_rect
			(start -0.508 0.9398)
			(end 0.508 -0.9398)
			(stroke
				(width 0)
				(type default)
			)
			(fill no)
			(layer "F.Fab")
		)
		(pad "1" smd custom
			(at 0 -0.4445)
			(size 0.1397 0.1397)
			(layers "F.Cu" "F.Mask" "F.Paste")
			(net "P3V3_STBY")
			(options
				(clearance outline)
				(anchor circle)
			)
			(primitives
				(gr_poly
					(pts
						(arc
							(start -0.1778 -0.2794)
							(mid -0.249642 -0.249642)
							(end -0.2794 -0.1778)
						)
						(arc
							(start -0.2794 0.1778)
							(mid -0.249642 0.249642)
							(end -0.1778 0.2794)
						)
						(arc
							(start 0.1778 0.2794)
							(mid 0.249642 0.249642)
							(end 0.2794 0.1778)
						)
						(arc
							(start 0.2794 -0.1778)
							(mid 0.249642 -0.249642)
							(end 0.1778 -0.2794)
						)
					)
					(width 0)
					(fill yes)
				)
			)
		)
		(pad "2" smd custom
			(at 0 0.4445)
			(size 0.1397 0.1397)
			(layers "F.Cu" "F.Mask" "F.Paste")
			(net "IO_EXP_HDD_PWR_A2")
			(options
				(clearance outline)
				(anchor circle)
			)
			(primitives
				(gr_poly
					(pts
						(arc
							(start -0.1778 -0.2794)
							(mid -0.249642 -0.249642)
							(end -0.2794 -0.1778)
						)
						(arc
							(start -0.2794 0.1778)
							(mid -0.249642 0.249642)
							(end -0.1778 0.2794)
						)
						(arc
							(start 0.1778 0.2794)
							(mid 0.249642 0.249642)
							(end 0.2794 0.1778)
						)
						(arc
							(start 0.2794 -0.1778)
							(mid 0.249642 -0.249642)
							(end 0.1778 -0.2794)
						)
					)
					(width 0)
					(fill yes)
				)
			)
		)
	)
	(footprint ""
		(layer "F.Cu")
		(at 94.215966 -69.342 180)
		(property "Reference" "SC1005"
			(at 0 0 180)
			(layer "F.SilkS")
			(hide yes)
			(effects
				(font
					(size 1.27 1.27)
				)
			)
		)
		(property "Value" "SCD1U16V2KX-3GP"
			(at 1.1811 -2.7051 180)
			(unlocked yes)
			(layer "F.Fab")
			(hide yes)
			(effects
				(font
					(size 1.016 1.016)
					(thickness 0.1524)
				)
			)
		)
		(property "Device Type" "C402H22"
			(at 1.1811 -4.2291 180)
			(unlocked yes)
			(layer "F.Fab")
			(hide yes)
			(effects
				(font
					(size 1.016 1.016)
					(thickness 0.1524)
				)
			)
		)
		(duplicate_pad_numbers_are_jumpers no)
		(fp_rect
			(start -0.4318 0.9525)
			(end 0.4318 -0.9525)
			(stroke
				(width 0)
				(type default)
			)
			(fill no)
			(layer "F.CrtYd")
		)
		(fp_rect
			(start -0.4318 0.9525)
			(end 0.4318 -0.9525)
			(stroke
				(width 0)
				(type default)
			)
			(fill no)
			(layer "F.Fab")
		)
		(pad "1" smd custom
			(at 0 -0.4445 180)
			(size 0.1524 0.1524)
			(layers "F.Cu" "F.Mask" "F.Paste")
			(net "P1V8_C")
			(options
				(clearance outline)
				(anchor circle)
			)
			(primitives
				(gr_poly
					(pts
						(arc
							(start 0.3048 -0.2032)
							(mid 0.275042 -0.275042)
							(end 0.2032 -0.3048)
						)
						(arc
							(start -0.2032 -0.3048)
							(mid -0.275042 -0.275042)
							(end -0.3048 -0.2032)
						)
						(arc
							(start -0.3048 0.2032)
							(mid -0.275042 0.275042)
							(end -0.2032 0.3048)
						)
						(arc
							(start 0.2032 0.3048)
							(mid 0.275042 0.275042)
							(end 0.3048 0.2032)
						)
					)
					(width 0)
					(fill yes)
				)
			)
		)
		(pad "2" smd custom
			(at 0 0.4445 180)
			(size 0.1524 0.1524)
			(layers "F.Cu" "F.Mask" "F.Paste")
			(net "GND")
			(options
				(clearance outline)
				(anchor circle)
			)
			(primitives
				(gr_poly
					(pts
						(arc
							(start 0.3048 -0.2032)
							(mid 0.275042 -0.275042)
							(end 0.2032 -0.3048)
						)
						(arc
							(start -0.2032 -0.3048)
							(mid -0.275042 -0.275042)
							(end -0.3048 -0.2032)
						)
						(arc
							(start -0.3048 0.2032)
							(mid -0.275042 0.275042)
							(end -0.2032 0.3048)
						)
						(arc
							(start 0.2032 0.3048)
							(mid 0.275042 0.275042)
							(end 0.3048 0.2032)
						)
					)
					(width 0)
					(fill yes)
				)
			)
		)
	)
	(footprint ""
		(layer "F.Cu")
		(at 182.372 -219.456 -90)
		(property "Reference" "C81"
			(at 0 0 270)
			(layer "F.SilkS")
			(hide yes)
			(effects
				(font
					(size 1.27 1.27)
				)
			)
		)
		(property "Value" "SCD1U16V2KX-3GP"
			(at 1.1811 -2.7051 270)
			(unlocked yes)
			(layer "F.Fab")
			(hide yes)
			(effects
				(font
					(size 1.016 1.016)
					(thickness 0.1524)
				)
			)
		)
		(property "Device Type" "C402H22"
			(at 1.1811 -4.2291 270)
			(unlocked yes)
			(layer "F.Fab")
			(hide yes)
			(effects
				(font
					(size 1.016 1.016)
					(thickness 0.1524)
				)
			)
		)
		(duplicate_pad_numbers_are_jumpers no)
		(fp_rect
			(start -0.4318 0.9525)
			(end 0.4318 -0.9525)
			(stroke
				(width 0)
				(type default)
			)
			(fill no)
			(layer "F.CrtYd")
		)
		(fp_rect
			(start -0.4318 0.9525)
			(end 0.4318 -0.9525)
			(stroke
				(width 0)
				(type default)
			)
			(fill no)
			(layer "F.Fab")
		)
		(pad "1" smd custom
			(at 0 -0.4445 270)
			(size 0.1524 0.1524)
			(layers "F.Cu" "F.Mask" "F.Paste")
			(net "P3V3_STBY")
			(options
				(clearance outline)
				(anchor circle)
			)
			(primitives
				(gr_poly
					(pts
						(arc
							(start 0.3048 -0.2032)
							(mid 0.275042 -0.275042)
							(end 0.2032 -0.3048)
						)
						(arc
							(start -0.2032 -0.3048)
							(mid -0.275042 -0.275042)
							(end -0.3048 -0.2032)
						)
						(arc
							(start -0.3048 0.2032)
							(mid -0.275042 0.275042)
							(end -0.2032 0.3048)
						)
						(arc
							(start 0.2032 0.3048)
							(mid 0.275042 0.275042)
							(end 0.3048 0.2032)
						)
					)
					(width 0)
					(fill yes)
				)
			)
		)
		(pad "2" smd custom
			(at 0 0.4445 270)
			(size 0.1524 0.1524)
			(layers "F.Cu" "F.Mask" "F.Paste")
			(net "GND")
			(options
				(clearance outline)
				(anchor circle)
			)
			(primitives
				(gr_poly
					(pts
						(arc
							(start 0.3048 -0.2032)
							(mid 0.275042 -0.275042)
							(end 0.2032 -0.3048)
						)
						(arc
							(start -0.2032 -0.3048)
							(mid -0.275042 -0.275042)
							(end -0.3048 -0.2032)
						)
						(arc
							(start -0.3048 0.2032)
							(mid -0.275042 0.275042)
							(end -0.2032 0.3048)
						)
						(arc
							(start 0.2032 0.3048)
							(mid 0.275042 0.275042)
							(end 0.3048 0.2032)
						)
					)
					(width 0)
					(fill yes)
				)
			)
		)
	)
	(footprint ""
		(layer "F.Cu")
		(at 86.976966 -88.011 180)
		(property "Reference" "SC1148"
			(at 0 0 180)
			(layer "F.SilkS")
			(hide yes)
			(effects
				(font
					(size 1.27 1.27)
				)
			)
		)
		(property "Value" "SC1U6D3V1MX-GP"
			(at 1.9177 2.0193 180)
			(unlocked yes)
			(layer "F.Fab")
			(hide yes)
			(effects
				(font
					(size 1.016 1.016)
					(thickness 0.1524)
				)
			)
		)
		(property "Device Type" "C0201H14"
			(at 1.9177 0.4953 180)
			(unlocked yes)
			(layer "F.Fab")
			(hide yes)
			(effects
				(font
					(size 1.016 1.016)
					(thickness 0.1524)
				)
			)
		)
		(duplicate_pad_numbers_are_jumpers no)
		(fp_rect
			(start -0.1524 0.3048)
			(end 0.1524 -0.3048)
			(stroke
				(width 0)
				(type default)
			)
			(fill no)
			(layer "F.CrtYd")
		)
		(fp_poly
			(pts
				(xy -0.2794 0.6477) (xy -0.2794 -0.6477) (xy 0.2794 -0.6477) (xy 0.2794 -0.1905) (xy 0.1524 -0.1905)
				(xy 0.1524 -0.3048) (xy -0.1524 -0.3048) (xy -0.1524 0.3048) (xy 0.1524 0.3048) (xy 0.1524 -0.1778)
				(xy 0.2794 -0.1778) (xy 0.2794 0.6477)
			)
			(stroke
				(width 0)
				(type default)
			)
			(fill no)
			(layer "F.CrtYd")
		)
		(fp_rect
			(start -0.2794 0.6477)
			(end 0.2794 -0.6477)
			(stroke
				(width 0)
				(type default)
			)
			(fill no)
			(layer "F.Fab")
		)
		(pad "1" smd custom
			(at 0 -0.2794 180)
			(size 0.0762 0.0762)
			(layers "F.Cu" "F.Mask" "F.Paste")
			(net "SYSPLL_VDDA18")
			(options
				(clearance outline)
				(anchor circle)
			)
			(primitives
				(gr_poly
					(pts
						(arc
							(start 0.1524 -0.127)
							(mid 0.137521 -0.162921)
							(end 0.1016 -0.1778)
						)
						(arc
							(start -0.1016 -0.1778)
							(mid -0.137521 -0.162921)
							(end -0.1524 -0.127)
						)
						(arc
							(start -0.1524 0.127)
							(mid -0.137521 0.162921)
							(end -0.1016 0.1778)
						)
						(arc
							(start 0.1016 0.1778)
							(mid 0.137521 0.162921)
							(end 0.1524 0.127)
						)
					)
					(width 0)
					(fill yes)
				)
			)
		)
		(pad "2" smd custom
			(at 0 0.2794 180)
			(size 0.0762 0.0762)
			(layers "F.Cu" "F.Mask" "F.Paste")
			(net "GND")
			(options
				(clearance outline)
				(anchor circle)
			)
			(primitives
				(gr_poly
					(pts
						(arc
							(start 0.1524 -0.127)
							(mid 0.137521 -0.162921)
							(end 0.1016 -0.1778)
						)
						(arc
							(start -0.1016 -0.1778)
							(mid -0.137521 -0.162921)
							(end -0.1524 -0.127)
						)
						(arc
							(start -0.1524 0.127)
							(mid -0.137521 0.162921)
							(end -0.1016 0.1778)
						)
						(arc
							(start 0.1016 0.1778)
							(mid 0.137521 0.162921)
							(end 0.1524 0.127)
						)
					)
					(width 0)
					(fill yes)
				)
			)
		)
	)
	(footprint ""
		(layer "F.Cu")
		(at 110.50397 -73.8124 90)
		(property "Reference" "SLED27"
			(at 0 0 90)
			(layer "F.SilkS")
			(hide yes)
			(effects
				(font
					(size 1.27 1.27)
				)
			)
		)
		(property "Value" "LED-YG-51-GP"
			(at -2.6924 -1.4224 90)
			(unlocked yes)
			(layer "F.Fab")
			(hide yes)
			(effects
				(font
					(size 1.016 1.016)
					(thickness 0.1524)
				)
			)
		)
		(property "Device Type" "LED1608AKH40"
			(at -2.6924 -2.9464 90)
			(unlocked yes)
			(layer "F.Fab")
			(hide yes)
			(effects
				(font
					(size 1.016 1.016)
					(thickness 0.1524)
				)
			)
		)
		(duplicate_pad_numbers_are_jumpers no)
		(fp_line
			(start 0.6604 -1.3716)
			(end 0.6604 1.3716)
			(stroke
				(width 0.1524)
				(type default)
			)
			(layer "F.SilkS")
		)
		(fp_line
			(start -0.6604 -1.3716)
			(end 0.6604 -1.3716)
			(stroke
				(width 0.1524)
				(type default)
			)
			(layer "F.SilkS")
		)
		(fp_line
			(start 0.6604 1.3716)
			(end -0.6604 1.3716)
			(stroke
				(width 0.1524)
				(type default)
			)
			(layer "F.SilkS")
		)
		(fp_line
			(start -0.6604 1.3716)
			(end -0.6604 -1.3716)
			(stroke
				(width 0.1524)
				(type default)
			)
			(layer "F.SilkS")
		)
		(fp_line
			(start -0.5969 1.5494)
			(end 0.5842 1.5494)
			(stroke
				(width 0.508)
				(type default)
			)
			(layer "F.SilkS")
		)
		(fp_line
			(start 0.7493 1.651)
			(end 0.7493 1.1811)
			(stroke
				(width 0.3302)
				(type default)
			)
			(layer "F.SilkS")
		)
		(fp_line
			(start -0.7493 1.651)
			(end -0.7493 1.1811)
			(stroke
				(width 0.3302)
				(type default)
			)
			(layer "F.SilkS")
		)
		(fp_rect
			(start -0.6223 1.3335)
			(end 0.6223 -1.3335)
			(stroke
				(width 0)
				(type default)
			)
			(fill no)
			(layer "F.CrtYd")
		)
		(fp_rect
			(start -0.6223 1.3335)
			(end 0.6223 -1.3335)
			(stroke
				(width 0)
				(type default)
			)
			(fill no)
			(layer "F.Fab")
		)
		(pad "A" smd custom
			(at 0 -0.762 90)
			(size 0.2159 0.2159)
			(layers "F.Cu" "F.Mask" "F.Paste")
			(net "EXP_HW_LED_R")
			(options
				(clearance outline)
				(anchor circle)
			)
			(primitives
				(gr_poly
					(pts
						(arc
							(start -0.3302 -0.4318)
							(mid -0.402042 -0.402042)
							(end -0.4318 -0.3302)
						)
						(arc
							(start -0.4318 0.3302)
							(mid -0.402042 0.402042)
							(end -0.3302 0.4318)
						)
						(arc
							(start 0.3302 0.4318)
							(mid 0.402042 0.402042)
							(end 0.4318 0.3302)
						)
						(arc
							(start 0.4318 -0.3302)
							(mid 0.402042 -0.402042)
							(end 0.3302 -0.4318)
						)
					)
					(width 0)
					(fill yes)
				)
			)
		)
		(pad "K" smd custom
			(at 0 0.762 90)
			(size 0.2159 0.2159)
			(layers "F.Cu" "F.Mask" "F.Paste")
			(net "EXP_HW_LED_D")
			(options
				(clearance outline)
				(anchor circle)
			)
			(primitives
				(gr_poly
					(pts
						(arc
							(start -0.3302 -0.4318)
							(mid -0.402042 -0.402042)
							(end -0.4318 -0.3302)
						)
						(arc
							(start -0.4318 0.3302)
							(mid -0.402042 0.402042)
							(end -0.3302 0.4318)
						)
						(arc
							(start 0.3302 0.4318)
							(mid 0.402042 0.402042)
							(end 0.4318 0.3302)
						)
						(arc
							(start 0.4318 -0.3302)
							(mid 0.402042 -0.402042)
							(end 0.3302 -0.4318)
						)
					)
					(width 0)
					(fill yes)
				)
			)
		)
	)
	(footprint ""
		(layer "F.Cu")
		(at 255.016 -17.653 90)
		(property "Reference" "L7"
			(at 0 0 90)
			(layer "F.SilkS")
			(hide yes)
			(effects
				(font
					(size 1.27 1.27)
				)
			)
		)
		(property "Value" "BLM21PG300SN-2GP"
			(at 0.0254 -5.6896 90)
			(unlocked yes)
			(layer "F.Fab")
			(hide yes)
			(effects
				(font
					(size 1.016 1.016)
					(thickness 0.1524)
				)
			)
		)
		(property "Device Type" "L20125H42"
			(at 0.0254 -7.5946 90)
			(unlocked yes)
			(layer "F.Fab")
			(hide yes)
			(effects
				(font
					(size 1.016 1.016)
					(thickness 0.1524)
				)
			)
		)
		(duplicate_pad_numbers_are_jumpers no)
		(fp_line
			(start 0.9144 -1.7018)
			(end -0.9144 -1.7018)
			(stroke
				(width 0.1524)
				(type default)
			)
			(layer "F.SilkS")
		)
		(fp_line
			(start -0.9144 -1.7018)
			(end -0.9144 1.7018)
			(stroke
				(width 0.1524)
				(type default)
			)
			(layer "F.SilkS")
		)
		(fp_line
			(start 0.9144 1.7018)
			(end 0.9144 -1.7018)
			(stroke
				(width 0.1524)
				(type default)
			)
			(layer "F.SilkS")
		)
		(fp_line
			(start -0.9144 1.7018)
			(end 0.9144 1.7018)
			(stroke
				(width 0.1524)
				(type default)
			)
			(layer "F.SilkS")
		)
		(fp_rect
			(start -1.0033 1.778)
			(end 1.0033 -1.778)
			(stroke
				(width 0)
				(type default)
			)
			(fill no)
			(layer "F.CrtYd")
		)
		(fp_poly
			(pts
				(xy -1.0033 -1.778) (xy 1.0033 -1.778) (xy 1.0033 1.778) (xy -1.0033 1.778)
			)
			(stroke
				(width 0)
				(type default)
			)
			(fill no)
			(layer "F.Fab")
		)
		(pad "1" smd rect
			(at 0 -0.9652 90)
			(size 1.397 1.143)
			(layers "F.Cu" "F.Mask" "F.Paste")
			(net "P5V_STBY")
		)
		(pad "2" smd rect
			(at 0 0.9652 90)
			(size 1.397 1.143)
			(layers "F.Cu" "F.Mask" "F.Paste")
			(net "P5V_USB_BP1_F")
		)
	)
)
